# T6G (Grand Teton) — schematic netlist excerpt (pin names and nets, part order shuffled) for the footprints in the layout excerpt that follows; sources: Cadence DE-HDL packaged netlist, KiCad conversion of 04192023_DAF0TMB3IC0_F0TG_MB_C_brd_V02_OCP.brd

C2469  Q_CAP  22UF 4V 20% X6S  pkg C0402  page 74 : A = PVDDCR_SOC_P1 ; B = GND
C2362  Q_CAP  22UF 4V 20% X6S  pkg C0402  page 73 : A = PVDDCR_CPU1_P1 ; B = GND

(kicad_pcb
	(version 20260206)
	(generator "pcbnew")
	(generator_version "10.0")
	(general
		(thickness 1.6)
		(legacy_teardrops no)
	)
	(paper "A4")
	(title_block
		(title "04192023_DAF0TMB3IC0_F0TG_MB_C_brd_V02_OCP.brd")
		(comment 1 "Grand Teton / footprints 6877-6878 of 8354")
	)
	(layers
		(0 "F.Cu" signal "TOP")
		(4 "In1.Cu" signal "GND")
		(6 "In2.Cu" signal "IN1")
		(8 "In3.Cu" signal "GND1")
		(10 "In4.Cu" signal "IN2")
		(12 "In5.Cu" signal "GND2")
		(14 "In6.Cu" signal "IN3")
		(16 "In7.Cu" signal "GND3")
		(18 "In8.Cu" signal "VCC")
		(20 "In9.Cu" signal "VCC1")
		(22 "In10.Cu" signal "GND4")
		(24 "In11.Cu" signal "IN4")
		(26 "In12.Cu" signal "GND5")
		(28 "In13.Cu" signal "IN5")
		(30 "In14.Cu" signal "GND6")
		(32 "In15.Cu" signal "IN6")
		(34 "In16.Cu" signal "GND7")
		(2 "B.Cu" signal "BOTTOM")
		(9 "F.Adhes" user "F.Adhesive")
		(11 "B.Adhes" user "B.Adhesive")
		(13 "F.Paste" user "Package Geometry/Pastemask Top")
		(15 "B.Paste" user "Package Geometry/Pastemask Bottom")
		(5 "F.SilkS" user "Ref Des/Silkscreen Top")
		(7 "B.SilkS" user "Ref Des/Silkscreen Bottom")
		(1 "F.Mask" user "Board Geometry/Soldermask Top")
		(3 "B.Mask" user "Board Geometry/Soldermask Bottom")
		(17 "Dwgs.User" user "User.Drawings")
		(19 "Cmts.User" user "User.Comments")
		(21 "Eco1.User" user "User.Eco1")
		(23 "Eco2.User" user "User.Eco2")
		(25 "Edge.Cuts" user "Board Geometry/Outline")
		(27 "Margin" user)
		(31 "F.CrtYd" user "Package Geometry/Place Bound Top")
		(29 "B.CrtYd" user "Package Geometry/Place Bound Bottom")
		(35 "F.Fab" user "Ref Des/Assembly Top")
		(33 "B.Fab" user "Ref Des/Assembly Bottom")
	)
	(footprint ""
		(layer "B.Cu")
		(at 118.658386 -269.307564 180)
		(property "Reference" "C2362"
			(at 0 0 0)
			(layer "B.SilkS")
			(hide yes)
			(effects
				(font
					(size 1.27 1.27)
				)
				(justify mirror)
			)
		)
		(property "Value" ""
			(at 0 0 0)
			(layer "B.Fab")
			(effects
				(font
					(size 1.27 1.27)
				)
				(justify mirror)
			)
		)
		(duplicate_pad_numbers_are_jumpers no)
		(fp_line
			(start 0.7874 0.4064)
			(end 0.7874 -0.4064)
			(stroke
				(width 0.1524)
				(type default)
			)
			(layer "B.SilkS")
		)
		(fp_line
			(start 0.7874 -0.4064)
			(end -0.7874 -0.4064)
			(stroke
				(width 0.1524)
				(type default)
			)
			(layer "B.SilkS")
		)
		(fp_line
			(start -0.7874 0.4064)
			(end 0.7874 0.4064)
			(stroke
				(width 0.1524)
				(type default)
			)
			(layer "B.SilkS")
		)
		(fp_line
			(start -0.7874 -0.4064)
			(end -0.7874 0.4064)
			(stroke
				(width 0.1524)
				(type default)
			)
			(layer "B.SilkS")
		)
		(fp_line
			(start 0.67945 0.3048)
			(end 0.67945 -0.305054)
			(stroke
				(width 0.1)
				(type default)
			)
			(layer "B.Fab")
		)
		(fp_line
			(start 0.67945 -0.305054)
			(end 0.12065 -0.305054)
			(stroke
				(width 0.1)
				(type default)
			)
			(layer "B.Fab")
		)
		(fp_line
			(start 0.12065 0.3048)
			(end 0.67945 0.3048)
			(stroke
				(width 0.1)
				(type default)
			)
			(layer "B.Fab")
		)
		(fp_line
			(start 0.12065 0.2794)
			(end 0.12065 0.3048)
			(stroke
				(width 0.1)
				(type default)
			)
			(layer "B.Fab")
		)
		(fp_line
			(start 0.12065 -0.2794)
			(end -0.12065 -0.2794)
			(stroke
				(width 0.1)
				(type default)
			)
			(layer "B.Fab")
		)
		(fp_line
			(start 0.12065 -0.305054)
			(end 0.12065 -0.2794)
			(stroke
				(width 0.1)
				(type default)
			)
			(layer "B.Fab")
		)
		(fp_line
			(start -0.120396 0.3048)
			(end -0.120396 0.2794)
			(stroke
				(width 0.1)
				(type default)
			)
			(layer "B.Fab")
		)
		(fp_line
			(start -0.120396 0.2794)
			(end 0.12065 0.2794)
			(stroke
				(width 0.1)
				(type default)
			)
			(layer "B.Fab")
		)
		(fp_line
			(start -0.12065 -0.2794)
			(end -0.12065 -0.3048)
			(stroke
				(width 0.1)
				(type default)
			)
			(layer "B.Fab")
		)
		(fp_line
			(start -0.12065 -0.3048)
			(end -0.67945 -0.3048)
			(stroke
				(width 0.1)
				(type default)
			)
			(layer "B.Fab")
		)
		(fp_line
			(start -0.67945 0.3048)
			(end -0.120396 0.3048)
			(stroke
				(width 0.1)
				(type default)
			)
			(layer "B.Fab")
		)
		(fp_line
			(start -0.67945 -0.3048)
			(end -0.67945 0.3048)
			(stroke
				(width 0.1)
				(type default)
			)
			(layer "B.Fab")
		)
		(pad "1" smd circle
			(at 0.40005 0)
			(size 0 0)
			(layers "B.Cu" "B.Mask" "B.Paste")
			(net "PVDDCR_CPU1_P1")
		)
		(pad "2" smd circle
			(at -0.40005 0)
			(size 0 0)
			(layers "B.Cu" "B.Mask" "B.Paste")
			(net "GND")
		)
	)
	(footprint ""
		(layer "B.Cu")
		(at 125.389386 -257.930396)
		(property "Reference" "C2469"
			(at 0 0 0)
			(layer "B.SilkS")
			(hide yes)
			(effects
				(font
					(size 1.27 1.27)
				)
				(justify mirror)
			)
		)
		(property "Value" ""
			(at 0 0 0)
			(layer "B.Fab")
			(effects
				(font
					(size 1.27 1.27)
				)
				(justify mirror)
			)
		)
		(duplicate_pad_numbers_are_jumpers no)
		(fp_line
			(start -0.7874 -0.4064)
			(end -0.7874 0.4064)
			(stroke
				(width 0.1524)
				(type default)
			)
			(layer "B.SilkS")
		)
		(fp_line
			(start -0.7874 0.4064)
			(end 0.7874 0.4064)
			(stroke
				(width 0.1524)
				(type default)
			)
			(layer "B.SilkS")
		)
		(fp_line
			(start 0.7874 -0.4064)
			(end -0.7874 -0.4064)
			(stroke
				(width 0.1524)
				(type default)
			)
			(layer "B.SilkS")
		)
		(fp_line
			(start 0.7874 0.4064)
			(end 0.7874 -0.4064)
			(stroke
				(width 0.1524)
				(type default)
			)
			(layer "B.SilkS")
		)
		(fp_line
			(start -0.67945 -0.3048)
			(end -0.67945 0.3048)
			(stroke
				(width 0.1)
				(type default)
			)
			(layer "B.Fab")
		)
		(fp_line
			(start -0.67945 0.3048)
			(end -0.120396 0.3048)
			(stroke
				(width 0.1)
				(type default)
			)
			(layer "B.Fab")
		)
		(fp_line
			(start -0.12065 -0.3048)
			(end -0.67945 -0.3048)
			(stroke
				(width 0.1)
				(type default)
			)
			(layer "B.Fab")
		)
		(fp_line
			(start -0.12065 -0.2794)
			(end -0.12065 -0.3048)
			(stroke
				(width 0.1)
				(type default)
			)
			(layer "B.Fab")
		)
		(fp_line
			(start -0.120396 0.2794)
			(end 0.12065 0.2794)
			(stroke
				(width 0.1)
				(type default)
			)
			(layer "B.Fab")
		)
		(fp_line
			(start -0.120396 0.3048)
			(end -0.120396 0.2794)
			(stroke
				(width 0.1)
				(type default)
			)
			(layer "B.Fab")
		)
		(fp_line
			(start 0.12065 -0.305054)
			(end 0.12065 -0.2794)
			(stroke
				(width 0.1)
				(type default)
			)
			(layer "B.Fab")
		)
		(fp_line
			(start 0.12065 -0.2794)
			(end -0.12065 -0.2794)
			(stroke
				(width 0.1)
				(type default)
			)
			(layer "B.Fab")
		)
		(fp_line
			(start 0.12065 0.2794)
			(end 0.12065 0.3048)
			(stroke
				(width 0.1)
				(type default)
			)
			(layer "B.Fab")
		)
		(fp_line
			(start 0.12065 0.3048)
			(end 0.67945 0.3048)
			(stroke
				(width 0.1)
				(type default)
			)
			(layer "B.Fab")
		)
		(fp_line
			(start 0.67945 -0.305054)
			(end 0.12065 -0.305054)
			(stroke
				(width 0.1)
				(type default)
			)
			(layer "B.Fab")
		)
		(fp_line
			(start 0.67945 0.3048)
			(end 0.67945 -0.305054)
			(stroke
				(width 0.1)
				(type default)
			)
			(layer "B.Fab")
		)
		(pad "1" smd circle
			(at 0.40005 0 180)
			(size 0 0)
			(layers "B.Cu" "B.Mask" "B.Paste")
			(net "PVDDCR_SOC_P1")
		)
		(pad "2" smd circle
			(at -0.40005 0 180)
			(size 0 0)
			(layers "B.Cu" "B.Mask" "B.Paste")
			(net "GND")
		)
	)
)
